# SCM (Grand Teton) — schematic netlist excerpt (pin names and nets, part order shuffled) for the footprints in the layout excerpt that follows; sources: Cadence DE-HDL packaged netlist, KiCad conversion of 12092022_DA0F0TMDCD0_F0T_Management_Board_D_brd_V3_OCP.brd

R49  Q_RES  0 5% CHIP  pkg 0402LF  page 22 : A = PWRGD_P1V0_AUX ; B = PWRGD_P1V0_AUX_R2

(kicad_pcb
	(version 20260206)
	(generator "pcbnew")
	(generator_version "10.0")
	(general
		(thickness 1.6)
		(legacy_teardrops no)
	)
	(paper "A4")
	(title_block
		(title "12092022_DA0F0TMDCD0_F0T_Management_Board_D_brd_V3_OCP.brd")
		(comment 1 "Grand Teton / footprints 31-31 of 1440")
	)
	(layers
		(0 "F.Cu" signal "TOP")
		(4 "In1.Cu" signal "GND")
		(6 "In2.Cu" signal "IN1")
		(8 "In3.Cu" signal "GND1")
		(10 "In4.Cu" signal "IN2")
		(12 "In5.Cu" signal "VCC")
		(14 "In6.Cu" signal "VCC1")
		(16 "In7.Cu" signal "IN3")
		(18 "In8.Cu" signal "GND2")
		(20 "In9.Cu" signal "IN4")
		(22 "In10.Cu" signal "GND3")
		(2 "B.Cu" signal "BOTTOM")
		(9 "F.Adhes" user "F.Adhesive")
		(11 "B.Adhes" user "B.Adhesive")
		(13 "F.Paste" user "Package Geometry/Pastemask Top")
		(15 "B.Paste" user "Package Geometry/Pastemask Bottom")
		(5 "F.SilkS" user "Ref Des/Silkscreen Top")
		(7 "B.SilkS" user "Ref Des/Silkscreen Bottom")
		(1 "F.Mask" user "Board Geometry/Soldermask Top")
		(3 "B.Mask" user "Board Geometry/Soldermask Bottom")
		(17 "Dwgs.User" user "User.Drawings")
		(19 "Cmts.User" user "User.Comments")
		(21 "Eco1.User" user "User.Eco1")
		(23 "Eco2.User" user "User.Eco2")
		(25 "Edge.Cuts" user "Board Geometry/Outline")
		(27 "Margin" user)
		(31 "F.CrtYd" user "Package Geometry/Place Bound Top")
		(29 "B.CrtYd" user "Package Geometry/Place Bound Bottom")
		(35 "F.Fab" user "Ref Des/Assembly Top")
		(33 "B.Fab" user "Ref Des/Assembly Bottom")
	)
	(footprint ""
		(layer "F.Cu")
		(at 34.93135 -36.151058 90)
		(property "Reference" "R49"
			(at 0 0 90)
			(layer "F.SilkS")
			(hide yes)
			(effects
				(font
					(size 1.27 1.27)
				)
			)
		)
		(property "Value" ""
			(at 0 0 90)
			(layer "F.Fab")
			(effects
				(font
					(size 1.27 1.27)
				)
			)
		)
		(duplicate_pad_numbers_are_jumpers no)
		(fp_line
			(start 0.7874 -0.4064)
			(end 0.7874 0.4064)
			(stroke
				(width 0.1524)
				(type default)
			)
			(layer "F.SilkS")
		)
		(fp_line
			(start -0.7874 -0.4064)
			(end 0.7874 -0.4064)
			(stroke
				(width 0.1524)
				(type default)
			)
			(layer "F.SilkS")
		)
		(fp_line
			(start 0.7874 0.4064)
			(end -0.7874 0.4064)
			(stroke
				(width 0.1524)
				(type default)
			)
			(layer "F.SilkS")
		)
		(fp_line
			(start -0.7874 0.4064)
			(end -0.7874 -0.4064)
			(stroke
				(width 0.1524)
				(type default)
			)
			(layer "F.SilkS")
		)
		(fp_line
			(start -0.12065 -0.305054)
			(end -0.12065 -0.2794)
			(stroke
				(width 0.1)
				(type default)
			)
			(layer "F.Fab")
		)
		(fp_line
			(start -0.67945 -0.305054)
			(end -0.12065 -0.305054)
			(stroke
				(width 0.1)
				(type default)
			)
			(layer "F.Fab")
		)
		(fp_line
			(start 0.67945 -0.3048)
			(end 0.67945 0.3048)
			(stroke
				(width 0.1)
				(type default)
			)
			(layer "F.Fab")
		)
		(fp_line
			(start 0.12065 -0.3048)
			(end 0.67945 -0.3048)
			(stroke
				(width 0.1)
				(type default)
			)
			(layer "F.Fab")
		)
		(fp_line
			(start 0.12065 -0.2794)
			(end 0.12065 -0.3048)
			(stroke
				(width 0.1)
				(type default)
			)
			(layer "F.Fab")
		)
		(fp_line
			(start -0.12065 -0.2794)
			(end 0.12065 -0.2794)
			(stroke
				(width 0.1)
				(type default)
			)
			(layer "F.Fab")
		)
		(fp_line
			(start 0.120396 0.2794)
			(end -0.12065 0.2794)
			(stroke
				(width 0.1)
				(type default)
			)
			(layer "F.Fab")
		)
		(fp_line
			(start -0.12065 0.2794)
			(end -0.12065 0.3048)
			(stroke
				(width 0.1)
				(type default)
			)
			(layer "F.Fab")
		)
		(fp_line
			(start 0.67945 0.3048)
			(end 0.120396 0.3048)
			(stroke
				(width 0.1)
				(type default)
			)
			(layer "F.Fab")
		)
		(fp_line
			(start 0.120396 0.3048)
			(end 0.120396 0.2794)
			(stroke
				(width 0.1)
				(type default)
			)
			(layer "F.Fab")
		)
		(fp_line
			(start -0.12065 0.3048)
			(end -0.67945 0.3048)
			(stroke
				(width 0.1)
				(type default)
			)
			(layer "F.Fab")
		)
		(fp_line
			(start -0.67945 0.3048)
			(end -0.67945 -0.305054)
			(stroke
				(width 0.1)
				(type default)
			)
			(layer "F.Fab")
		)
		(pad "1" smd circle
			(at -0.40005 0 90)
			(size 0 0)
			(layers "F.Cu" "F.Mask" "F.Paste")
			(net "PWRGD_P1V0_AUX")
		)
		(pad "2" smd circle
			(at 0.40005 0 90)
			(size 0 0)
			(layers "F.Cu" "F.Mask" "F.Paste")
			(net "PWRGD_P1V0_AUX_R2")
		)
	)
)
